(kicad_pcb
	(version 20260206)
	(generator "pcbnew")
	(generator_version "10.0")
	(general
		(thickness 1.6)
		(legacy_teardrops no)
	)
	(paper "A4")
	(title_block
		(title "04192023_DAF0TMB3IC0_F0TG_MB_C_brd_V02_OCP.brd")
		(comment 1 "Grand Teton / footprint 3955 of 8354 (U25), pads 976-1085 of 6102")
	)
	(layers
		(0 "F.Cu" signal "TOP")
		(4 "In1.Cu" signal "GND")
		(6 "In2.Cu" signal "IN1")
		(8 "In3.Cu" signal "GND1")
		(10 "In4.Cu" signal "IN2")
		(12 "In5.Cu" signal "GND2")
		(14 "In6.Cu" signal "IN3")
		(16 "In7.Cu" signal "GND3")
		(18 "In8.Cu" signal "VCC")
		(20 "In9.Cu" signal "VCC1")
		(22 "In10.Cu" signal "GND4")
		(24 "In11.Cu" signal "IN4")
		(26 "In12.Cu" signal "GND5")
		(28 "In13.Cu" signal "IN5")
		(30 "In14.Cu" signal "GND6")
		(32 "In15.Cu" signal "IN6")
		(34 "In16.Cu" signal "GND7")
		(2 "B.Cu" signal "BOTTOM")
		(9 "F.Adhes" user "F.Adhesive")
		(11 "B.Adhes" user "B.Adhesive")
		(13 "F.Paste" user "Package Geometry/Pastemask Top")
		(15 "B.Paste" user "Package Geometry/Pastemask Bottom")
		(5 "F.SilkS" user "Ref Des/Silkscreen Top")
		(7 "B.SilkS" user "Ref Des/Silkscreen Bottom")
		(1 "F.Mask" user "Board Geometry/Soldermask Top")
		(3 "B.Mask" user "Board Geometry/Soldermask Bottom")
		(17 "Dwgs.User" user "User.Drawings")
		(19 "Cmts.User" user "User.Comments")
		(21 "Eco1.User" user "User.Eco1")
		(23 "Eco2.User" user "User.Eco2")
		(25 "Edge.Cuts" user "Board Geometry/Outline")
		(27 "Margin" user)
		(31 "F.CrtYd" user "Package Geometry/Place Bound Top")
		(29 "B.CrtYd" user "Package Geometry/Place Bound Bottom")
		(35 "F.Fab" user "Ref Des/Assembly Top")
		(33 "B.Fab" user "Ref Des/Assembly Bottom")
	)
	(footprint ""
		(layer "F.Cu")
		(at 359.867962 -258.880102 180)
		(property "Reference" "U25"
			(at -45.78477 -62.086744 0)
			(unlocked yes)
			(layer "F.SilkS")
			(effects
				(font
					(size 0.7874 0.5842)
					(thickness 0.1524)
				)
			)
		)
		(property "Value" ""
			(at 0 0 180)
			(layer "F.Fab")
			(effects
				(font
					(size 1.27 1.27)
				)
			)
		)
		(duplicate_pad_numbers_are_jumpers no)
		(pad "AN53" smd circle
			(at 13.780008 -10.889996 180)
			(size 0.450088 0.450088)
			(layers "F.Cu" "F.Mask" "F.Paste")
			(net "GMI_CPU0_G1_CPU1_G3_TX_DN<13>")
		)
		(pad "AN54" smd circle
			(at 14.720062 -10.889996 180)
			(size 0.450088 0.450088)
			(layers "F.Cu" "F.Mask" "F.Paste")
			(net "GND")
		)
		(pad "AN55" smd circle
			(at 15.660116 -10.889996 180)
			(size 0.450088 0.450088)
			(layers "F.Cu" "F.Mask" "F.Paste")
			(net "M_C_CPU0_SA_DQS_DP<9>")
		)
		(pad "AN56" smd circle
			(at 16.599916 -10.889996 180)
			(size 0.450088 0.450088)
			(layers "F.Cu" "F.Mask" "F.Paste")
			(net "GND")
		)
		(pad "AN57" smd circle
			(at 17.53997 -10.889996 180)
			(size 0.450088 0.450088)
			(layers "F.Cu" "F.Mask" "F.Paste")
			(net "M_C_CPU0_SA_CB<4>")
		)
		(pad "AN58" smd circle
			(at 18.480024 -10.889996 180)
			(size 0.450088 0.450088)
			(layers "F.Cu" "F.Mask" "F.Paste")
			(net "GND")
		)
		(pad "AN59" smd circle
			(at 19.420078 -10.889996 180)
			(size 0.450088 0.450088)
			(layers "F.Cu" "F.Mask" "F.Paste")
			(net "M_D_CPU0_SA_DQS_DP<9>")
		)
		(pad "AN60" smd circle
			(at 20.359878 -10.889996 180)
			(size 0.450088 0.450088)
			(layers "F.Cu" "F.Mask" "F.Paste")
			(net "M_D_CPU0_SA_CB<4>")
		)
		(pad "AN61" smd circle
			(at 21.299932 -10.889996 180)
			(size 0.450088 0.450088)
			(layers "F.Cu" "F.Mask" "F.Paste")
			(net "GND")
		)
		(pad "AN62" smd circle
			(at 22.239986 -10.889996 180)
			(size 0.450088 0.450088)
			(layers "F.Cu" "F.Mask" "F.Paste")
			(net "M_B_CPU0_SA_DQS_DP<9>")
		)
		(pad "AN63" smd circle
			(at 23.18004 -10.889996 180)
			(size 0.450088 0.450088)
			(layers "F.Cu" "F.Mask" "F.Paste")
			(net "GND")
		)
		(pad "AN64" smd circle
			(at 24.120094 -10.889996 180)
			(size 0.450088 0.450088)
			(layers "F.Cu" "F.Mask" "F.Paste")
			(net "M_B_CPU0_SA_CB<4>")
		)
		(pad "AN65" smd circle
			(at 25.059894 -10.889996 180)
			(size 0.450088 0.450088)
			(layers "F.Cu" "F.Mask" "F.Paste")
			(net "GND")
		)
		(pad "AN66" smd circle
			(at 25.999948 -10.889996 180)
			(size 0.450088 0.450088)
			(layers "F.Cu" "F.Mask" "F.Paste")
			(net "M_F_CPU0_SA_DQS_DP<9>")
		)
		(pad "AN67" smd circle
			(at 26.940002 -10.889996 180)
			(size 0.450088 0.450088)
			(layers "F.Cu" "F.Mask" "F.Paste")
			(net "M_F_CPU0_SA_CB<4>")
		)
		(pad "AN68" smd circle
			(at 27.880056 -10.889996 180)
			(size 0.450088 0.450088)
			(layers "F.Cu" "F.Mask" "F.Paste")
			(net "GND")
		)
		(pad "AN69" smd circle
			(at 28.82011 -10.889996 180)
			(size 0.450088 0.450088)
			(layers "F.Cu" "F.Mask" "F.Paste")
			(net "M_E_CPU0_SA_DQS_DP<9>")
		)
		(pad "AN70" smd circle
			(at 29.75991 -10.889996 180)
			(size 0.450088 0.450088)
			(layers "F.Cu" "F.Mask" "F.Paste")
			(net "GND")
		)
		(pad "AN71" smd circle
			(at 30.699964 -10.889996 180)
			(size 0.450088 0.450088)
			(layers "F.Cu" "F.Mask" "F.Paste")
			(net "M_E_CPU0_SA_CB<4>")
		)
		(pad "AN72" smd circle
			(at 31.640018 -10.889996 180)
			(size 0.450088 0.450088)
			(layers "F.Cu" "F.Mask" "F.Paste")
			(net "GND")
		)
		(pad "AN73" smd circle
			(at 32.580072 -10.889996 180)
			(size 0.450088 0.450088)
			(layers "F.Cu" "F.Mask" "F.Paste")
			(net "M_A_CPU0_SA_DQS_DP<9>")
		)
		(pad "AN74" smd circle
			(at 33.519872 -10.889996 180)
			(size 0.450088 0.450088)
			(layers "F.Cu" "F.Mask" "F.Paste")
			(net "M_A_CPU0_SA_CB<4>")
		)
		(pad "AN75" smd circle
			(at 34.459926 -10.889996 180)
			(size 0.450088 0.450088)
			(layers "F.Cu" "F.Mask" "F.Paste")
			(net "GND")
		)
		(pad "AP2" smd circle
			(at -33.690052 -10.07999 180)
			(size 0.450088 0.450088)
			(layers "F.Cu" "F.Mask" "F.Paste")
			(net "M_G_CPU0_SA_CB<6>")
		)
		(pad "AP3" smd circle
			(at -32.749998 -10.07999 180)
			(size 0.450088 0.450088)
			(layers "F.Cu" "F.Mask" "F.Paste")
			(net "GND")
		)
		(pad "AP4" smd circle
			(at -31.809944 -10.07999 180)
			(size 0.450088 0.450088)
			(layers "F.Cu" "F.Mask" "F.Paste")
			(net "M_G_CPU0_SA_CB<5>")
		)
		(pad "AP5" smd circle
			(at -30.86989 -10.07999 180)
			(size 0.450088 0.450088)
			(layers "F.Cu" "F.Mask" "F.Paste")
			(net "GND")
		)
		(pad "AP6" smd circle
			(at -29.93009 -10.07999 180)
			(size 0.450088 0.450088)
			(layers "F.Cu" "F.Mask" "F.Paste")
			(net "M_K_CPU0_SA_CB<6>")
		)
		(pad "AP7" smd circle
			(at -28.990036 -10.07999 180)
			(size 0.450088 0.450088)
			(layers "F.Cu" "F.Mask" "F.Paste")
			(net "M_K_CPU0_SA_CB<5>")
		)
		(pad "AP8" smd circle
			(at -28.049982 -10.07999 180)
			(size 0.450088 0.450088)
			(layers "F.Cu" "F.Mask" "F.Paste")
			(net "GND")
		)
		(pad "AP9" smd circle
			(at -27.109928 -10.07999 180)
			(size 0.450088 0.450088)
			(layers "F.Cu" "F.Mask" "F.Paste")
			(net "M_L_CPU0_SA_CB<6>")
		)
		(pad "AP10" smd circle
			(at -26.170128 -10.07999 180)
			(size 0.450088 0.450088)
			(layers "F.Cu" "F.Mask" "F.Paste")
			(net "GND")
		)
		(pad "AP11" smd circle
			(at -25.230074 -10.07999 180)
			(size 0.450088 0.450088)
			(layers "F.Cu" "F.Mask" "F.Paste")
			(net "M_L_CPU0_SA_CB<5>")
		)
		(pad "AP12" smd circle
			(at -24.29002 -10.07999 180)
			(size 0.450088 0.450088)
			(layers "F.Cu" "F.Mask" "F.Paste")
			(net "GND")
		)
		(pad "AP13" smd circle
			(at -23.349966 -10.07999 180)
			(size 0.450088 0.450088)
			(layers "F.Cu" "F.Mask" "F.Paste")
			(net "M_H_CPU0_SA_CB<6>")
		)
		(pad "AP14" smd circle
			(at -22.409912 -10.07999 180)
			(size 0.450088 0.450088)
			(layers "F.Cu" "F.Mask" "F.Paste")
			(net "M_H_CPU0_SA_CB<5>")
		)
		(pad "AP15" smd circle
			(at -21.470112 -10.07999 180)
			(size 0.450088 0.450088)
			(layers "F.Cu" "F.Mask" "F.Paste")
			(net "GND")
		)
		(pad "AP16" smd circle
			(at -20.530058 -10.07999 180)
			(size 0.450088 0.450088)
			(layers "F.Cu" "F.Mask" "F.Paste")
			(net "M_J_CPU0_SA_CB<6>")
		)
		(pad "AP17" smd circle
			(at -19.590004 -10.07999 180)
			(size 0.450088 0.450088)
			(layers "F.Cu" "F.Mask" "F.Paste")
			(net "GND")
		)
		(pad "AP18" smd circle
			(at -18.64995 -10.07999 180)
			(size 0.450088 0.450088)
			(layers "F.Cu" "F.Mask" "F.Paste")
			(net "M_J_CPU0_SA_CB<5>")
		)
		(pad "AP19" smd circle
			(at -17.709896 -10.07999 180)
			(size 0.450088 0.450088)
			(layers "F.Cu" "F.Mask" "F.Paste")
			(net "GND")
		)
		(pad "AP20" smd circle
			(at -16.770096 -10.07999 180)
			(size 0.450088 0.450088)
			(layers "F.Cu" "F.Mask" "F.Paste")
			(net "M_I_CPU0_SA_CB<6>")
		)
		(pad "AP21" smd circle
			(at -15.830042 -10.07999 180)
			(size 0.450088 0.450088)
			(layers "F.Cu" "F.Mask" "F.Paste")
			(net "M_I_CPU0_SA_CB<5>")
		)
		(pad "AP22" smd circle
			(at -14.889988 -10.07999 180)
			(size 0.450088 0.450088)
			(layers "F.Cu" "F.Mask" "F.Paste")
			(net "GND")
		)
		(pad "AP23" smd circle
			(at -13.949934 -10.07999 180)
			(size 0.450088 0.450088)
			(layers "F.Cu" "F.Mask" "F.Paste")
			(net "PVDDCR_CPU0_P0")
		)
		(pad "AP24" smd circle
			(at -13.00988 -10.07999 180)
			(size 0.450088 0.450088)
			(layers "F.Cu" "F.Mask" "F.Paste")
			(net "PVDDCR_CPU0_P0")
		)
		(pad "AP25" smd circle
			(at -12.07008 -10.07999 180)
			(size 0.450088 0.450088)
			(layers "F.Cu" "F.Mask" "F.Paste")
			(net "GND")
		)
		(pad "AP26" smd circle
			(at -11.130026 -10.07999 180)
			(size 0.450088 0.450088)
			(layers "F.Cu" "F.Mask" "F.Paste")
			(net "PVDDCR_CPU0_P0")
		)
		(pad "AP27" smd circle
			(at -10.189972 -10.07999 180)
			(size 0.450088 0.450088)
			(layers "F.Cu" "F.Mask" "F.Paste")
			(net "PVDDCR_CPU0_P0")
		)
		(pad "AP28" smd circle
			(at -9.249918 -10.07999 180)
			(size 0.450088 0.450088)
			(layers "F.Cu" "F.Mask" "F.Paste")
			(net "GND")
		)
		(pad "AP29" smd circle
			(at -8.310118 -10.07999 180)
			(size 0.450088 0.450088)
			(layers "F.Cu" "F.Mask" "F.Paste")
			(net "PVDDCR_CPU0_P0")
		)
		(pad "AP30" smd circle
			(at -7.370064 -10.07999 180)
			(size 0.450088 0.450088)
			(layers "F.Cu" "F.Mask" "F.Paste")
			(net "PVDDCR_CPU0_P0")
		)
		(pad "AP31" smd circle
			(at -6.43001 -10.07999 180)
			(size 0.450088 0.450088)
			(layers "F.Cu" "F.Mask" "F.Paste")
			(net "GND")
		)
		(pad "AP32" smd circle
			(at -5.489956 -10.07999 180)
			(size 0.450088 0.450088)
			(layers "F.Cu" "F.Mask" "F.Paste")
			(net "PVDDCR_CPU0_P0")
		)
		(pad "AP33" smd circle
			(at -4.549902 -10.07999 180)
			(size 0.450088 0.450088)
			(layers "F.Cu" "F.Mask" "F.Paste")
			(net "PVDDCR_CPU0_P0")
		)
		(pad "AP34" smd circle
			(at -3.610102 -10.07999 180)
			(size 0.450088 0.450088)
			(layers "F.Cu" "F.Mask" "F.Paste")
			(net "GND")
		)
		(pad "AP35" smd circle
			(at -2.670048 -10.07999 180)
			(size 0.450088 0.450088)
			(layers "F.Cu" "F.Mask" "F.Paste")
			(net "P5E_CPU0_G3_RX_DN<15>")
		)
		(pad "AP36" smd circle
			(at -1.729994 -10.07999 180)
			(size 0.450088 0.450088)
			(layers "F.Cu" "F.Mask" "F.Paste")
			(net "P5E_CPU0_G3_RX_DP<15>")
		)
		(pad "AP37" smd circle
			(at -0.78994 -10.07999 180)
			(size 0.450088 0.450088)
			(layers "F.Cu" "F.Mask" "F.Paste")
			(net "GND")
		)
		(pad "AP39" smd circle
			(at 1.089914 -10.07999 180)
			(size 0.450088 0.450088)
			(layers "F.Cu" "F.Mask" "F.Paste")
			(net "GND")
		)
		(pad "AP40" smd circle
			(at 2.029968 -10.07999 180)
			(size 0.450088 0.450088)
			(layers "F.Cu" "F.Mask" "F.Paste")
			(net "GMI_CPU0_G1_CPU1_G3_TX_DP<0>")
		)
		(pad "AP41" smd circle
			(at 2.970022 -10.07999 180)
			(size 0.450088 0.450088)
			(layers "F.Cu" "F.Mask" "F.Paste")
			(net "GMI_CPU0_G1_CPU1_G3_TX_DN<0>")
		)
		(pad "AP42" smd circle
			(at 3.910076 -10.07999 180)
			(size 0.450088 0.450088)
			(layers "F.Cu" "F.Mask" "F.Paste")
			(net "GND")
		)
		(pad "AP43" smd circle
			(at 4.849876 -10.07999 180)
			(size 0.450088 0.450088)
			(layers "F.Cu" "F.Mask" "F.Paste")
			(net "PVDDCR_CPU0_P0")
		)
		(pad "AP44" smd circle
			(at 5.78993 -10.07999 180)
			(size 0.450088 0.450088)
			(layers "F.Cu" "F.Mask" "F.Paste")
			(net "PVDDCR_CPU0_P0")
		)
		(pad "AP45" smd circle
			(at 6.729984 -10.07999 180)
			(size 0.450088 0.450088)
			(layers "F.Cu" "F.Mask" "F.Paste")
			(net "GND")
		)
		(pad "AP46" smd circle
			(at 7.670038 -10.07999 180)
			(size 0.450088 0.450088)
			(layers "F.Cu" "F.Mask" "F.Paste")
			(net "PVDDCR_CPU0_P0")
		)
		(pad "AP47" smd circle
			(at 8.610092 -10.07999 180)
			(size 0.450088 0.450088)
			(layers "F.Cu" "F.Mask" "F.Paste")
			(net "PVDDCR_CPU0_P0")
		)
		(pad "AP48" smd circle
			(at 9.549892 -10.07999 180)
			(size 0.450088 0.450088)
			(layers "F.Cu" "F.Mask" "F.Paste")
			(net "GND")
		)
		(pad "AP49" smd circle
			(at 10.489946 -10.07999 180)
			(size 0.450088 0.450088)
			(layers "F.Cu" "F.Mask" "F.Paste")
			(net "PVDDCR_CPU0_P0")
		)
		(pad "AP50" smd circle
			(at 11.43 -10.07999 180)
			(size 0.450088 0.450088)
			(layers "F.Cu" "F.Mask" "F.Paste")
			(net "PVDDCR_CPU0_P0")
		)
		(pad "AP51" smd circle
			(at 12.370054 -10.07999 180)
			(size 0.450088 0.450088)
			(layers "F.Cu" "F.Mask" "F.Paste")
			(net "GND")
		)
		(pad "AP52" smd circle
			(at 13.310108 -10.07999 180)
			(size 0.450088 0.450088)
			(layers "F.Cu" "F.Mask" "F.Paste")
			(net "PVDDCR_CPU0_P0")
		)
		(pad "AP53" smd circle
			(at 14.249908 -10.07999 180)
			(size 0.450088 0.450088)
			(layers "F.Cu" "F.Mask" "F.Paste")
			(net "PVDDCR_CPU0_P0")
		)
		(pad "AP54" smd circle
			(at 15.189962 -10.07999 180)
			(size 0.450088 0.450088)
			(layers "F.Cu" "F.Mask" "F.Paste")
			(net "GND")
		)
		(pad "AP55" smd circle
			(at 16.130016 -10.07999 180)
			(size 0.450088 0.450088)
			(layers "F.Cu" "F.Mask" "F.Paste")
			(net "M_C_CPU0_SA_CB<5>")
		)
		(pad "AP56" smd circle
			(at 17.07007 -10.07999 180)
			(size 0.450088 0.450088)
			(layers "F.Cu" "F.Mask" "F.Paste")
			(net "M_C_CPU0_SA_CB<6>")
		)
		(pad "AP57" smd circle
			(at 18.010124 -10.07999 180)
			(size 0.450088 0.450088)
			(layers "F.Cu" "F.Mask" "F.Paste")
			(net "GND")
		)
		(pad "AP58" smd circle
			(at 18.949924 -10.07999 180)
			(size 0.450088 0.450088)
			(layers "F.Cu" "F.Mask" "F.Paste")
			(net "M_D_CPU0_SA_CB<5>")
		)
		(pad "AP59" smd circle
			(at 19.889978 -10.07999 180)
			(size 0.450088 0.450088)
			(layers "F.Cu" "F.Mask" "F.Paste")
			(net "GND")
		)
		(pad "AP60" smd circle
			(at 20.830032 -10.07999 180)
			(size 0.450088 0.450088)
			(layers "F.Cu" "F.Mask" "F.Paste")
			(net "M_D_CPU0_SA_CB<6>")
		)
		(pad "AP61" smd circle
			(at 21.770086 -10.07999 180)
			(size 0.450088 0.450088)
			(layers "F.Cu" "F.Mask" "F.Paste")
			(net "GND")
		)
		(pad "AP62" smd circle
			(at 22.709886 -10.07999 180)
			(size 0.450088 0.450088)
			(layers "F.Cu" "F.Mask" "F.Paste")
			(net "M_B_CPU0_SA_CB<5>")
		)
		(pad "AP63" smd circle
			(at 23.64994 -10.07999 180)
			(size 0.450088 0.450088)
			(layers "F.Cu" "F.Mask" "F.Paste")
			(net "M_B_CPU0_SA_CB<6>")
		)
		(pad "AP64" smd circle
			(at 24.589994 -10.07999 180)
			(size 0.450088 0.450088)
			(layers "F.Cu" "F.Mask" "F.Paste")
			(net "GND")
		)
		(pad "AP65" smd circle
			(at 25.530048 -10.07999 180)
			(size 0.450088 0.450088)
			(layers "F.Cu" "F.Mask" "F.Paste")
			(net "M_F_CPU0_SA_CB<5>")
		)
		(pad "AP66" smd circle
			(at 26.470102 -10.07999 180)
			(size 0.450088 0.450088)
			(layers "F.Cu" "F.Mask" "F.Paste")
			(net "GND")
		)
		(pad "AP67" smd circle
			(at 27.409902 -10.07999 180)
			(size 0.450088 0.450088)
			(layers "F.Cu" "F.Mask" "F.Paste")
			(net "M_F_CPU0_SA_CB<6>")
		)
		(pad "AP68" smd circle
			(at 28.349956 -10.07999 180)
			(size 0.450088 0.450088)
			(layers "F.Cu" "F.Mask" "F.Paste")
			(net "GND")
		)
		(pad "AP69" smd circle
			(at 29.29001 -10.07999 180)
			(size 0.450088 0.450088)
			(layers "F.Cu" "F.Mask" "F.Paste")
			(net "M_E_CPU0_SA_CB<5>")
		)
		(pad "AP70" smd circle
			(at 30.230064 -10.07999 180)
			(size 0.450088 0.450088)
			(layers "F.Cu" "F.Mask" "F.Paste")
			(net "M_E_CPU0_SA_CB<6>")
		)
		(pad "AP71" smd circle
			(at 31.170118 -10.07999 180)
			(size 0.450088 0.450088)
			(layers "F.Cu" "F.Mask" "F.Paste")
			(net "GND")
		)
		(pad "AP72" smd circle
			(at 32.109918 -10.07999 180)
			(size 0.450088 0.450088)
			(layers "F.Cu" "F.Mask" "F.Paste")
			(net "M_A_CPU0_SA_CB<5>")
		)
		(pad "AP73" smd circle
			(at 33.049972 -10.07999 180)
			(size 0.450088 0.450088)
			(layers "F.Cu" "F.Mask" "F.Paste")
			(net "GND")
		)
		(pad "AP74" smd circle
			(at 33.990026 -10.07999 180)
			(size 0.450088 0.450088)
			(layers "F.Cu" "F.Mask" "F.Paste")
			(net "M_A_CPU0_SA_CB<6>")
		)
		(pad "AR1" smd circle
			(at -34.159952 -9.269984 180)
			(size 0.450088 0.450088)
			(layers "F.Cu" "F.Mask" "F.Paste")
			(net "GND")
		)
		(pad "AR2" smd circle
			(at -33.219898 -9.269984 180)
			(size 0.450088 0.450088)
			(layers "F.Cu" "F.Mask" "F.Paste")
			(net "M_G_CPU0_ALERT_R_N")
		)
		(pad "AR3" smd circle
			(at -32.280098 -9.269984 180)
			(size 0.450088 0.450088)
			(layers "F.Cu" "F.Mask" "F.Paste")
			(net "M_G_CPU0_SA_CB<7>")
		)
		(pad "AR4" smd circle
			(at -31.340044 -9.269984 180)
			(size 0.450088 0.450088)
			(layers "F.Cu" "F.Mask" "F.Paste")
			(net "PVDDCR_SOC_P0")
		)
		(pad "AR5" smd circle
			(at -30.39999 -9.269984 180)
			(size 0.450088 0.450088)
			(layers "F.Cu" "F.Mask" "F.Paste")
			(net "GND")
		)
		(pad "AR6" smd circle
			(at -29.459936 -9.269984 180)
			(size 0.450088 0.450088)
			(layers "F.Cu" "F.Mask" "F.Paste")
			(net "GND")
		)
		(pad "AR7" smd circle
			(at -28.519882 -9.269984 180)
			(size 0.450088 0.450088)
			(layers "F.Cu" "F.Mask" "F.Paste")
			(net "M_K_CPU0_SA_CB<7>")
		)
		(pad "AR8" smd circle
			(at -27.580082 -9.269984 180)
			(size 0.450088 0.450088)
			(layers "F.Cu" "F.Mask" "F.Paste")
			(net "GND")
		)
		(pad "AR9" smd circle
			(at -26.640028 -9.269984 180)
			(size 0.450088 0.450088)
			(layers "F.Cu" "F.Mask" "F.Paste")
			(net "GND")
		)
		(pad "AR10" smd circle
			(at -25.699974 -9.269984 180)
			(size 0.450088 0.450088)
			(layers "F.Cu" "F.Mask" "F.Paste")
			(net "M_L_CPU0_SA_CB<7>")
		)
		(pad "AR11" smd circle
			(at -24.75992 -9.269984 180)
			(size 0.450088 0.450088)
			(layers "F.Cu" "F.Mask" "F.Paste")
			(net "PVDDCR_SOC_P0")
		)
		(pad "AR12" smd circle
			(at -23.82012 -9.269984 180)
			(size 0.450088 0.450088)
			(layers "F.Cu" "F.Mask" "F.Paste")
			(net "GND")
		)
		(pad "AR13" smd circle
			(at -22.880066 -9.269984 180)
			(size 0.450088 0.450088)
			(layers "F.Cu" "F.Mask" "F.Paste")
			(net "GND")
		)
		(pad "AR14" smd circle
			(at -21.940012 -9.269984 180)
			(size 0.450088 0.450088)
			(layers "F.Cu" "F.Mask" "F.Paste")
			(net "M_H_CPU0_SA_CB<7>")
		)
		(pad "AR15" smd circle
			(at -20.999958 -9.269984 180)
			(size 0.450088 0.450088)
			(layers "F.Cu" "F.Mask" "F.Paste")
			(net "GND")
		)
	)
)
